(kicad_pcb
	(version 20260206)
	(generator "pcbnew")
	(generator_version "10.0")
	(general
		(thickness 1.6)
		(legacy_teardrops no)
	)
	(paper "A4")
	(title_block
		(title "Bryce Canyon_F.DPB_16315-1-OCP.brd")
		(comment 1 "Bryce Canyon / footprints 416-422 of 2223")
	)
	(layers
		(0 "F.Cu" signal "TOP")
		(4 "In1.Cu" signal "L2GND")
		(6 "In2.Cu" signal "L3")
		(8 "In3.Cu" signal "L4GND")
		(10 "In4.Cu" signal "L5")
		(12 "In5.Cu" signal "L6VCC")
		(14 "In6.Cu" signal "L7VCC")
		(16 "In7.Cu" signal "L8")
		(18 "In8.Cu" signal "L9GND")
		(20 "In9.Cu" signal "L10")
		(22 "In10.Cu" signal "L11GND")
		(2 "B.Cu" signal "BOTTOM")
		(9 "F.Adhes" user "F.Adhesive")
		(11 "B.Adhes" user "B.Adhesive")
		(13 "F.Paste" user "Package Geometry/Pastemask Top")
		(15 "B.Paste" user "Package Geometry/Pastemask Bottom")
		(5 "F.SilkS" user "Ref Des/Silkscreen Top")
		(7 "B.SilkS" user "Ref Des/Silkscreen Bottom")
		(1 "F.Mask" user "Board Geometry/Soldermask Top")
		(3 "B.Mask" user "Board Geometry/Soldermask Bottom")
		(17 "Dwgs.User" user "User.Drawings")
		(19 "Cmts.User" user "User.Comments")
		(21 "Eco1.User" user "User.Eco1")
		(23 "Eco2.User" user "User.Eco2")
		(25 "Edge.Cuts" user "Board Geometry/Outline")
		(27 "Margin" user)
		(31 "F.CrtYd" user "Package Geometry/Place Bound Top")
		(29 "B.CrtYd" user "Package Geometry/Place Bound Bottom")
		(35 "F.Fab" user "Ref Des/Assembly Top")
		(33 "B.Fab" user "Ref Des/Assembly Bottom")
	)
	(footprint ""
		(layer "F.Cu")
		(at 262.255 -272.288)
		(property "Reference" "R108"
			(at 0 0 0)
			(layer "F.SilkS")
			(hide yes)
			(effects
				(font
					(size 1.27 1.27)
				)
			)
		)
		(property "Value" "4K7R2F-GP"
			(at 0.064008 -3.993896 0)
			(unlocked yes)
			(layer "F.Fab")
			(hide yes)
			(effects
				(font
					(size 1.016 1.016)
					(thickness 0.1524)
				)
			)
		)
		(property "Device Type" "R402H16"
			(at 0.064008 -5.517896 0)
			(unlocked yes)
			(layer "F.Fab")
			(hide yes)
			(effects
				(font
					(size 1.016 1.016)
					(thickness 0.1524)
				)
			)
		)
		(duplicate_pad_numbers_are_jumpers no)
		(fp_line
			(start -0.508 -0.9398)
			(end -0.508 0.9398)
			(stroke
				(width 0.1524)
				(type default)
			)
			(layer "F.SilkS")
		)
		(fp_line
			(start 0.508 -0.9398)
			(end -0.508 -0.9398)
			(stroke
				(width 0.1524)
				(type default)
			)
			(layer "F.SilkS")
		)
		(fp_rect
			(start -0.508 0.9398)
			(end 0.508 -0.9398)
			(stroke
				(width 0)
				(type default)
			)
			(fill no)
			(layer "F.CrtYd")
		)
		(fp_rect
			(start -0.508 0.9398)
			(end 0.508 -0.9398)
			(stroke
				(width 0)
				(type default)
			)
			(fill no)
			(layer "F.Fab")
		)
		(pad "1" smd custom
			(at 0 -0.4445)
			(size 0.1397 0.1397)
			(layers "F.Cu" "F.Mask" "F.Paste")
			(net "IO_EXP0_HDD_FAULT_A1")
			(options
				(clearance outline)
				(anchor circle)
			)
			(primitives
				(gr_poly
					(pts
						(arc
							(start -0.1778 -0.2794)
							(mid -0.249642 -0.249642)
							(end -0.2794 -0.1778)
						)
						(arc
							(start -0.2794 0.1778)
							(mid -0.249642 0.249642)
							(end -0.1778 0.2794)
						)
						(arc
							(start 0.1778 0.2794)
							(mid 0.249642 0.249642)
							(end 0.2794 0.1778)
						)
						(arc
							(start 0.2794 -0.1778)
							(mid 0.249642 -0.249642)
							(end 0.1778 -0.2794)
						)
					)
					(width 0)
					(fill yes)
				)
			)
		)
		(pad "2" smd custom
			(at 0 0.4445)
			(size 0.1397 0.1397)
			(layers "F.Cu" "F.Mask" "F.Paste")
			(net "GND")
			(options
				(clearance outline)
				(anchor circle)
			)
			(primitives
				(gr_poly
					(pts
						(arc
							(start -0.1778 -0.2794)
							(mid -0.249642 -0.249642)
							(end -0.2794 -0.1778)
						)
						(arc
							(start -0.2794 0.1778)
							(mid -0.249642 0.249642)
							(end -0.1778 0.2794)
						)
						(arc
							(start 0.1778 0.2794)
							(mid 0.249642 0.249642)
							(end 0.2794 0.1778)
						)
						(arc
							(start 0.2794 -0.1778)
							(mid 0.249642 -0.249642)
							(end 0.1778 -0.2794)
						)
					)
					(width 0)
					(fill yes)
				)
			)
		)
	)
	(footprint ""
		(layer "F.Cu")
		(at 280.0604 19.9136 90)
		(property "Reference" "R15"
			(at 0 0 90)
			(layer "F.SilkS")
			(hide yes)
			(effects
				(font
					(size 1.27 1.27)
				)
			)
		)
		(property "Value" "0R2J-2-GP"
			(at 0.064008 -3.993896 90)
			(unlocked yes)
			(layer "F.Fab")
			(hide yes)
			(effects
				(font
					(size 1.016 1.016)
					(thickness 0.1524)
				)
			)
		)
		(property "Device Type" "R402H16"
			(at 0.064008 -5.517896 90)
			(unlocked yes)
			(layer "F.Fab")
			(hide yes)
			(effects
				(font
					(size 1.016 1.016)
					(thickness 0.1524)
				)
			)
		)
		(duplicate_pad_numbers_are_jumpers no)
		(fp_line
			(start 0.508 -0.9398)
			(end -0.508 -0.9398)
			(stroke
				(width 0.1524)
				(type default)
			)
			(layer "F.SilkS")
		)
		(fp_line
			(start -0.508 -0.9398)
			(end -0.508 0.9398)
			(stroke
				(width 0.1524)
				(type default)
			)
			(layer "F.SilkS")
		)
		(fp_rect
			(start -0.508 0.9398)
			(end 0.508 -0.9398)
			(stroke
				(width 0)
				(type default)
			)
			(fill no)
			(layer "F.CrtYd")
		)
		(fp_rect
			(start -0.508 0.9398)
			(end 0.508 -0.9398)
			(stroke
				(width 0)
				(type default)
			)
			(fill no)
			(layer "F.Fab")
		)
		(pad "1" smd custom
			(at 0 -0.4445 90)
			(size 0.1397 0.1397)
			(layers "F.Cu" "F.Mask" "F.Paste")
			(net "DPB_PWR_BTN_BUF_A")
			(options
				(clearance outline)
				(anchor circle)
			)
			(primitives
				(gr_poly
					(pts
						(arc
							(start -0.1778 -0.2794)
							(mid -0.249642 -0.249642)
							(end -0.2794 -0.1778)
						)
						(arc
							(start -0.2794 0.1778)
							(mid -0.249642 0.249642)
							(end -0.1778 0.2794)
						)
						(arc
							(start 0.1778 0.2794)
							(mid 0.249642 0.249642)
							(end 0.2794 0.1778)
						)
						(arc
							(start 0.2794 -0.1778)
							(mid 0.249642 -0.249642)
							(end 0.1778 -0.2794)
						)
					)
					(width 0)
					(fill yes)
				)
			)
		)
		(pad "2" smd custom
			(at 0 0.4445 90)
			(size 0.1397 0.1397)
			(layers "F.Cu" "F.Mask" "F.Paste")
			(net "DPB_PWR_BTN_A")
			(options
				(clearance outline)
				(anchor circle)
			)
			(primitives
				(gr_poly
					(pts
						(arc
							(start -0.1778 -0.2794)
							(mid -0.249642 -0.249642)
							(end -0.2794 -0.1778)
						)
						(arc
							(start -0.2794 0.1778)
							(mid -0.249642 0.249642)
							(end -0.1778 0.2794)
						)
						(arc
							(start 0.1778 0.2794)
							(mid 0.249642 0.249642)
							(end 0.2794 0.1778)
						)
						(arc
							(start 0.2794 -0.1778)
							(mid 0.249642 -0.249642)
							(end 0.1778 -0.2794)
						)
					)
					(width 0)
					(fill yes)
				)
			)
		)
	)
	(footprint ""
		(layer "F.Cu")
		(at 144.723866 -143.848074 -90)
		(property "Reference" "R1060"
			(at 0 0 270)
			(layer "F.SilkS")
			(hide yes)
			(effects
				(font
					(size 1.27 1.27)
				)
			)
		)
		(property "Value" "100KR2F-L1-GP"
			(at 0.064008 -3.993896 270)
			(unlocked yes)
			(layer "F.Fab")
			(hide yes)
			(effects
				(font
					(size 1.016 1.016)
					(thickness 0.1524)
				)
			)
		)
		(property "Device Type" "R402H16"
			(at 0.064008 -5.517896 270)
			(unlocked yes)
			(layer "F.Fab")
			(hide yes)
			(effects
				(font
					(size 1.016 1.016)
					(thickness 0.1524)
				)
			)
		)
		(duplicate_pad_numbers_are_jumpers no)
		(fp_line
			(start -0.508 -0.9398)
			(end -0.508 0.9398)
			(stroke
				(width 0.1524)
				(type default)
			)
			(layer "F.SilkS")
		)
		(fp_line
			(start 0.508 -0.9398)
			(end -0.508 -0.9398)
			(stroke
				(width 0.1524)
				(type default)
			)
			(layer "F.SilkS")
		)
		(fp_rect
			(start -0.508 0.9398)
			(end 0.508 -0.9398)
			(stroke
				(width 0)
				(type default)
			)
			(fill no)
			(layer "F.CrtYd")
		)
		(fp_rect
			(start -0.508 0.9398)
			(end 0.508 -0.9398)
			(stroke
				(width 0)
				(type default)
			)
			(fill no)
			(layer "F.Fab")
		)
		(pad "1" smd custom
			(at 0 -0.4445 270)
			(size 0.1397 0.1397)
			(layers "F.Cu" "F.Mask" "F.Paste")
			(net "MB0_VCAP_R")
			(options
				(clearance outline)
				(anchor circle)
			)
			(primitives
				(gr_poly
					(pts
						(arc
							(start -0.1778 -0.2794)
							(mid -0.249642 -0.249642)
							(end -0.2794 -0.1778)
						)
						(arc
							(start -0.2794 0.1778)
							(mid -0.249642 0.249642)
							(end -0.1778 0.2794)
						)
						(arc
							(start 0.1778 0.2794)
							(mid 0.249642 0.249642)
							(end 0.2794 0.1778)
						)
						(arc
							(start 0.2794 -0.1778)
							(mid 0.249642 -0.249642)
							(end 0.1778 -0.2794)
						)
					)
					(width 0)
					(fill yes)
				)
			)
		)
		(pad "2" smd custom
			(at 0 0.4445 270)
			(size 0.1397 0.1397)
			(layers "F.Cu" "F.Mask" "F.Paste")
			(net "MB0_ISTART_R")
			(options
				(clearance outline)
				(anchor circle)
			)
			(primitives
				(gr_poly
					(pts
						(arc
							(start -0.1778 -0.2794)
							(mid -0.249642 -0.249642)
							(end -0.2794 -0.1778)
						)
						(arc
							(start -0.2794 0.1778)
							(mid -0.249642 0.249642)
							(end -0.1778 0.2794)
						)
						(arc
							(start 0.1778 0.2794)
							(mid 0.249642 0.249642)
							(end 0.2794 0.1778)
						)
						(arc
							(start 0.2794 -0.1778)
							(mid 0.249642 -0.249642)
							(end 0.1778 -0.2794)
						)
					)
					(width 0)
					(fill yes)
				)
			)
		)
	)
	(footprint ""
		(layer "F.Cu")
		(at 79.924148 -167.060118 90)
		(property "Reference" "R459"
			(at 0 0 90)
			(layer "F.SilkS")
			(hide yes)
			(effects
				(font
					(size 1.27 1.27)
				)
			)
		)
		(property "Value" "4K7R2J-2-GP"
			(at 0.064008 -3.993896 90)
			(unlocked yes)
			(layer "F.Fab")
			(hide yes)
			(effects
				(font
					(size 1.016 1.016)
					(thickness 0.1524)
				)
			)
		)
		(property "Device Type" "R402H16"
			(at 0.064008 -5.517896 90)
			(unlocked yes)
			(layer "F.Fab")
			(hide yes)
			(effects
				(font
					(size 1.016 1.016)
					(thickness 0.1524)
				)
			)
		)
		(duplicate_pad_numbers_are_jumpers no)
		(fp_line
			(start 0.508 -0.9398)
			(end -0.508 -0.9398)
			(stroke
				(width 0.1524)
				(type default)
			)
			(layer "F.SilkS")
		)
		(fp_line
			(start -0.508 -0.9398)
			(end -0.508 0.9398)
			(stroke
				(width 0.1524)
				(type default)
			)
			(layer "F.SilkS")
		)
		(fp_rect
			(start -0.508 0.9398)
			(end 0.508 -0.9398)
			(stroke
				(width 0)
				(type default)
			)
			(fill no)
			(layer "F.CrtYd")
		)
		(fp_rect
			(start -0.508 0.9398)
			(end 0.508 -0.9398)
			(stroke
				(width 0)
				(type default)
			)
			(fill no)
			(layer "F.Fab")
		)
		(pad "1" smd custom
			(at 0 -0.4445 90)
			(size 0.1397 0.1397)
			(layers "F.Cu" "F.Mask" "F.Paste")
			(net "P12V_A")
			(options
				(clearance outline)
				(anchor circle)
			)
			(primitives
				(gr_poly
					(pts
						(arc
							(start -0.1778 -0.2794)
							(mid -0.249642 -0.249642)
							(end -0.2794 -0.1778)
						)
						(arc
							(start -0.2794 0.1778)
							(mid -0.249642 0.249642)
							(end -0.1778 0.2794)
						)
						(arc
							(start 0.1778 0.2794)
							(mid 0.249642 0.249642)
							(end 0.2794 0.1778)
						)
						(arc
							(start 0.2794 -0.1778)
							(mid 0.249642 -0.249642)
							(end 0.1778 -0.2794)
						)
					)
					(width 0)
					(fill yes)
				)
			)
		)
		(pad "2" smd custom
			(at 0 0.4445 90)
			(size 0.1397 0.1397)
			(layers "F.Cu" "F.Mask" "F.Paste")
			(net "SW_HDD_P14")
			(options
				(clearance outline)
				(anchor circle)
			)
			(primitives
				(gr_poly
					(pts
						(arc
							(start -0.1778 -0.2794)
							(mid -0.249642 -0.249642)
							(end -0.2794 -0.1778)
						)
						(arc
							(start -0.2794 0.1778)
							(mid -0.249642 0.249642)
							(end -0.1778 0.2794)
						)
						(arc
							(start 0.1778 0.2794)
							(mid 0.249642 0.249642)
							(end 0.2794 0.1778)
						)
						(arc
							(start 0.2794 -0.1778)
							(mid 0.249642 -0.249642)
							(end 0.1778 -0.2794)
						)
					)
					(width 0)
					(fill yes)
				)
			)
		)
	)
	(footprint ""
		(layer "F.Cu")
		(at 172.593 -54.523894 90)
		(property "Reference" "C426"
			(at 0 0 90)
			(layer "F.SilkS")
			(hide yes)
			(effects
				(font
					(size 1.27 1.27)
				)
			)
		)
		(property "Value" "SCD033U25V2KX-GP"
			(at 1.1811 -2.7051 90)
			(unlocked yes)
			(layer "F.Fab")
			(hide yes)
			(effects
				(font
					(size 1.016 1.016)
					(thickness 0.1524)
				)
			)
		)
		(property "Device Type" "C402H22"
			(at 1.1811 -4.2291 90)
			(unlocked yes)
			(layer "F.Fab")
			(hide yes)
			(effects
				(font
					(size 1.016 1.016)
					(thickness 0.1524)
				)
			)
		)
		(duplicate_pad_numbers_are_jumpers no)
		(fp_rect
			(start -0.4318 0.9525)
			(end 0.4318 -0.9525)
			(stroke
				(width 0)
				(type default)
			)
			(fill no)
			(layer "F.CrtYd")
		)
		(fp_rect
			(start -0.4318 0.9525)
			(end 0.4318 -0.9525)
			(stroke
				(width 0)
				(type default)
			)
			(fill no)
			(layer "F.Fab")
		)
		(pad "1" smd custom
			(at 0 -0.4445 90)
			(size 0.1524 0.1524)
			(layers "F.Cu" "F.Mask" "F.Paste")
			(net "P12V_A")
			(options
				(clearance outline)
				(anchor circle)
			)
			(primitives
				(gr_poly
					(pts
						(arc
							(start 0.3048 -0.2032)
							(mid 0.275042 -0.275042)
							(end 0.2032 -0.3048)
						)
						(arc
							(start -0.2032 -0.3048)
							(mid -0.275042 -0.275042)
							(end -0.3048 -0.2032)
						)
						(arc
							(start -0.3048 0.2032)
							(mid -0.275042 0.275042)
							(end -0.2032 0.3048)
						)
						(arc
							(start 0.2032 0.3048)
							(mid 0.275042 0.275042)
							(end 0.3048 0.2032)
						)
					)
					(width 0)
					(fill yes)
				)
			)
		)
		(pad "2" smd custom
			(at 0 0.4445 90)
			(size 0.1524 0.1524)
			(layers "F.Cu" "F.Mask" "F.Paste")
			(net "SW_HDD_N29")
			(options
				(clearance outline)
				(anchor circle)
			)
			(primitives
				(gr_poly
					(pts
						(arc
							(start 0.3048 -0.2032)
							(mid 0.275042 -0.275042)
							(end 0.2032 -0.3048)
						)
						(arc
							(start -0.2032 -0.3048)
							(mid -0.275042 -0.275042)
							(end -0.3048 -0.2032)
						)
						(arc
							(start -0.3048 0.2032)
							(mid -0.275042 0.275042)
							(end -0.2032 0.3048)
						)
						(arc
							(start 0.2032 0.3048)
							(mid 0.275042 0.275042)
							(end 0.3048 0.2032)
						)
					)
					(width 0)
					(fill yes)
				)
			)
		)
	)
	(footprint ""
		(layer "F.Cu")
		(at 190.807086 -41.307512 180)
		(property "Reference" "R801"
			(at 0 0 180)
			(layer "F.SilkS")
			(hide yes)
			(effects
				(font
					(size 1.27 1.27)
				)
			)
		)
		(property "Value" "220R3F-1-GP"
			(at -0.0254 -2.5146 180)
			(unlocked yes)
			(layer "F.Fab")
			(hide yes)
			(effects
				(font
					(size 1.016 1.016)
					(thickness 0.1524)
				)
			)
		)
		(property "Device Type" "R603H22"
			(at -0.0254 -4.0386 180)
			(unlocked yes)
			(layer "F.Fab")
			(hide yes)
			(effects
				(font
					(size 1.016 1.016)
					(thickness 0.1524)
				)
			)
		)
		(duplicate_pad_numbers_are_jumpers no)
		(fp_line
			(start 0.2032 0)
			(end 0.4826 0)
			(stroke
				(width 0.2032)
				(type default)
			)
			(layer "F.SilkS")
		)
		(fp_line
			(start -0.4826 0)
			(end -0.2032 0)
			(stroke
				(width 0.2032)
				(type default)
			)
			(layer "F.SilkS")
		)
		(fp_rect
			(start -0.5842 1.3335)
			(end 0.5842 -1.3335)
			(stroke
				(width 0)
				(type default)
			)
			(fill no)
			(layer "F.CrtYd")
		)
		(fp_rect
			(start -0.5842 1.3335)
			(end 0.5842 -1.3335)
			(stroke
				(width 0)
				(type default)
			)
			(fill no)
			(layer "F.Fab")
		)
		(pad "1" smd custom
			(at 0 -0.762 180)
			(size 0.2159 0.2159)
			(layers "F.Cu" "F.Mask" "F.Paste")
			(net "HDD_PRSNT_29")
			(options
				(clearance outline)
				(anchor circle)
			)
			(primitives
				(gr_poly
					(pts
						(arc
							(start -0.3302 -0.4318)
							(mid -0.402042 -0.402042)
							(end -0.4318 -0.3302)
						)
						(arc
							(start -0.4318 0.3302)
							(mid -0.402042 0.402042)
							(end -0.3302 0.4318)
						)
						(arc
							(start 0.3302 0.4318)
							(mid 0.402042 0.402042)
							(end 0.4318 0.3302)
						)
						(arc
							(start 0.4318 -0.3302)
							(mid 0.402042 -0.402042)
							(end 0.3302 -0.4318)
						)
					)
					(width 0)
					(fill yes)
				)
			)
		)
		(pad "2" smd custom
			(at 0 0.762 180)
			(size 0.2159 0.2159)
			(layers "F.Cu" "F.Mask" "F.Paste")
			(net "DRIVE_A_29_INS")
			(options
				(clearance outline)
				(anchor circle)
			)
			(primitives
				(gr_poly
					(pts
						(arc
							(start -0.3302 -0.4318)
							(mid -0.402042 -0.402042)
							(end -0.4318 -0.3302)
						)
						(arc
							(start -0.4318 0.3302)
							(mid -0.402042 0.402042)
							(end -0.3302 0.4318)
						)
						(arc
							(start 0.3302 0.4318)
							(mid 0.402042 0.402042)
							(end 0.4318 0.3302)
						)
						(arc
							(start 0.4318 -0.3302)
							(mid 0.402042 -0.402042)
							(end 0.3302 -0.4318)
						)
					)
					(width 0)
					(fill yes)
				)
			)
		)
	)
	(footprint ""
		(layer "F.Cu")
		(at 18.906998 -294.683942 90)
		(property "Reference" "R959"
			(at 0 0 90)
			(layer "F.SilkS")
			(hide yes)
			(effects
				(font
					(size 1.27 1.27)
				)
			)
		)
		(property "Value" "2R6F-GP"
			(at -0.0508 -4.8514 90)
			(unlocked yes)
			(layer "F.Fab")
			(hide yes)
			(effects
				(font
					(size 1.016 1.016)
					(thickness 0.1524)
				)
			)
		)
		(property "Device Type" "R1206H26"
			(at 0 -6.3754 90)
			(unlocked yes)
			(layer "F.Fab")
			(hide yes)
			(effects
				(font
					(size 1.016 1.016)
					(thickness 0.1524)
				)
			)
		)
		(duplicate_pad_numbers_are_jumpers no)
		(fp_line
			(start 1.016 -2.2352)
			(end 1.016 2.2352)
			(stroke
				(width 0.1524)
				(type default)
			)
			(layer "F.SilkS")
		)
		(fp_line
			(start -1.016 -2.2352)
			(end 1.016 -2.2352)
			(stroke
				(width 0.1524)
				(type default)
			)
			(layer "F.SilkS")
		)
		(fp_line
			(start 1.016 2.2352)
			(end -1.016 2.2352)
			(stroke
				(width 0.1524)
				(type default)
			)
			(layer "F.SilkS")
		)
		(fp_line
			(start -1.016 2.2352)
			(end -1.016 -2.2352)
			(stroke
				(width 0.1524)
				(type default)
			)
			(layer "F.SilkS")
		)
		(fp_rect
			(start -1.0922 2.3114)
			(end 1.0922 -2.3114)
			(stroke
				(width 0)
				(type default)
			)
			(fill no)
			(layer "F.CrtYd")
		)
		(fp_poly
			(pts
				(xy -1.0922 -2.3114) (xy 1.0922 -2.3114) (xy 1.0922 2.3114) (xy -1.0922 2.3114)
			)
			(stroke
				(width 0)
				(type default)
			)
			(fill no)
			(layer "F.Fab")
		)
		(pad "1" smd rect
			(at 0 -1.397 90)
			(size 1.651 1.27)
			(layers "F.Cu" "F.Mask" "F.Paste")
			(net "P12V_HDD0")
		)
		(pad "2" smd rect
			(at 0 1.397 90)
			(size 1.651 1.27)
			(layers "F.Cu" "F.Mask" "F.Paste")
			(net "12V_PRE_0")
		)
	)
)
